# BARRELEYE-G2-SXM2 RISER BOARD-EVT-X00-BOM-X01-20171102_Final.xls.xlsx — Single-Sole Source Parts List (bom)
| FOXCONN TECHNOLOGY GROUP |  |  |  |  |  |  |  |  |  |  |  |  |  |  |  |  |  |
| BILL OF MATERIAL |  |  |  |  |  |  |  |  |  |  |  |  |  |  |  |  |  |
| REV OF  BOM | X01 | CUSTOMER | <name> |  | CUSTOMER P/N |  | PWA P/N： | PWA DESCRIPTION |  |  | PRODUCT CODE |  |  | PWA REV |  | DATE | 43041 |
| Sourcing (Single or Sole | Critical Commodity (Y or N) | Component Class (1, 2, other) | Customer PSL (Y/N) | Item Number | Foxconn P/N | Customer P/N | Part Description | Mfr. 1 | Mfr Part # 1 | Proposed Mfr. 2 | Proposed Mfr. 2 PN | Qty | RoHS Status | Location | 2nd Source Qual Build: | Customer Comments | ODM Comments |
|  |  |  |  | 2 | 62110GF00-021-G | - | ECAP,470uF,+/-20%,25V,105C,G,SMD10X10,ESR<=80mOhm | NIPPON CHEMI-CON CORPORATION | EMZA250ADA471MJA0G |  |  | 1 | G | CE1 |  |  |  |
|  |  |  |  | 3 | 62120BC00-022-G | - | SPEA,CAP,560uF,+/-20%,16V,105C,G,SMD8*11.9,ESR<=14mOhm | SANYO ELECTRIC CO., LTD. | 16SVPF560M |  |  | 4 | G | CE2,CE6,CE7,CE8 |  |  |  |
|  |  |  |  | 10 | 521107T00-289-G | KX549 | LED,Gre,LTST-C190KGKT,2.4V,30mA,G,SMD0603 | LITE-ON TECHNOLOGY CORPORATION | LTST-C190KGKT |  |  | 1 | G | LED_GPU_PWR_PG |  |  |  |
|  |  |  |  | 28 | 320143Y00-183-G | - | IC,Regulator,TPS548A20RVER,ADJ,15A,G,VQFN-28,SMD | TEXAS INSTRUMENTS | TPS548A20RVER |  |  | 1 | G | PSTU1 |  |  |  |
|  |  |  |  | 36 | 32022BB00-183-G |  | IC,Power Controller,TPS3808G30DBVR,G,SOT23-6,SMD | TEXAS INSTRUMENTS | TPS3808G30DBVR |  |  | 1 | G | U45 |  |  |  |
|  |  |  |  | 37 | 31050AE00-183-G | - | IC,Buffer,SN74LVC2G07DCKR,1.65~5.5V,G,SC70-6,SMD | TEXAS INSTRUMENTS | SN74LVC2G07DCKR |  |  | 2 | G | U75,U172 |  |  |  |
|  |  |  |  | 39 | 310201K00-185-G |  | IC,Trigger,NC7SZ74K8X,1.65~5.5V,G,US8-8,SMD | FAIRCHILD SEMICONDUCTOR CORP | NC7SZ74K8X |  |  | 1 | G | U164 |  |  |  |
|  |  |  |  | 43 | 311001L00-031-G |  | IC,Translator,PCA9517ADP,0.9~5.5V;2.7~5.5V,G,TSSOP-8,SMD | NXP SEMICONDUCTORS | PCA9517ADP |  |  | 2 | G | U170,U171 |  |  |  |
|  |  |  |  | 44 | 34071BS00-245-G |  | CONN,SAS,V/T,0.6mm,30u,G,SMD-74 | AMPHENOL SHANGHAI CORP. | U10-K074-26BT |  |  | 2 | G | J_CP1_NVLINK_BOTTOM,J_CP0_NVLINK_BOTTOM |  |  |  |
|  |  |  |  | 45 | 34071BR00-245-G |  | CONN,SAS,V/T,0.6mm,30u,G,SMD-74 | AMPHENOL SHANGHAI CORP. | U10-K074-260T |  |  | 2 | G | J_CP1_NVLINK_TOP,J_CP0_NVLINK_TOP |  |  |  |
|  |  |  |  | 46 | 340636800-600-G |  | CONN,Header,Power,2X9,V/T,Whi,4.2mm,G,DIP-18 | FOXCONN TECHNOLOGY CO.,LTD. | HM3509E-HP1 |  |  | 1 | G | J_GPU_PWR |  |  |  |
|  |  |  |  | 47 | 34131VV00-G78-G |  | CONN,BTB,1.27mm,30u,G,SMD-400 | FCI CONNECTORS HONGKONG LTD. | 84740-102LF |  |  | 4 | G | J_PEX_GPU1,J_NVLINK_GPU1,J_PEX_GPU0,J_NVLINK_GPU0 |  |  |  |
|  |  |  |  | 48 | 340303U00-600-G | 6Y810 | CONN,Slot,PCIE-16X,V/T,Bla,1mm,15u,G,DIP-164 | FOXCONN TECHNOLOGY CO.,LTD. | 2EG0821V-22D |  |  | 2 | G | J_PCIE3,J_PCIE4 |  |  |  |
|  |  |  |  | 49 | 340653G00-317-G |  | CONN,Header,Shrouded,2X11,V/T,Bla,2mm,30u,G,SMD-22 | MOLEX INCORPORATED | 87832-6023 |  |  | 1 | G | J_SIDEBAND |  |  |  |
|  |  |  |  | 50 | 3406A9J00-309-G |  | CONN,Header,Shrouded,2X5,V/T,Bla,1.27mm,30u,G,SMD-10 | SAMTEC INC. | ASP-193835-01 |  |  | 2 | G | J16,J17 |  |  |  |
|  |  |  |  | 51 | 630366300-57M-G |  | IND,100nH@100KHz,+/-10%,51A,0.29mOhm,SHLD,G,SMD | COOPER BUSSMANN, INC. | FP0906R1-R10-R |  |  | 2 | G | L9,L10 |  |  |  |
|  |  |  |  | 53 | 34081AL00-653-G |  | CONN,Switch,slide,Whi,100mA,50V,G,SMD-8 | DIPTRONICS MANUFACTURING INC. | EM-04-Q-T/R |  |  | 1 | G | SW2 |  |  |  |
|  |  |  |  | 54 | 34080C200-653-G | - | CONN,Switch,slide,25mA,24V,Whi,G,SMD-4 | DIPTRONICS MANUFACTURING INC. | DHNF-02-T-V-T/R |  |  | 1 | G | SW3 |  |  |  |
